# S9S_MB_2U (Grand Teton) — schematic netlist excerpt (pin names and nets, part order shuffled) for the footprints in the layout excerpt that follows; sources: Cadence DE-HDL packaged netlist, KiCad conversion of 03242023_DA0F0TMBIJ0_F0T_Motherboard_J_brd_V01_OCP.brd

PR3840  Q_RES  71.5K 1% EMPTY  pkg 0402LF  page 157 : A = P12V_OCP_SFF ; B = P12V_OCP_OV_FB_1
C435  Q_CAP  22UF 4V 20% X6S  pkg C0402  page 77 : A = PVCCFA_EHV_FIVRA_CPU1 ; B = GND

(kicad_pcb
	(version 20260206)
	(generator "pcbnew")
	(generator_version "10.0")
	(general
		(thickness 1.6)
		(legacy_teardrops no)
	)
	(paper "A4")
	(title_block
		(title "03242023_DA0F0TMBIJ0_F0T_Motherboard_J_brd_V01_OCP.brd")
		(comment 1 "Grand Teton / footprints 98-99 of 6105")
	)
	(layers
		(0 "F.Cu" signal "TOP")
		(4 "In1.Cu" signal "GND")
		(6 "In2.Cu" signal "IN1")
		(8 "In3.Cu" signal "GND1")
		(10 "In4.Cu" signal "IN2")
		(12 "In5.Cu" signal "GND2")
		(14 "In6.Cu" signal "IN3")
		(16 "In7.Cu" signal "GND3")
		(18 "In8.Cu" signal "VCC")
		(20 "In9.Cu" signal "VCC1")
		(22 "In10.Cu" signal "GND4")
		(24 "In11.Cu" signal "IN4")
		(26 "In12.Cu" signal "GND5")
		(28 "In13.Cu" signal "IN5")
		(30 "In14.Cu" signal "GND6")
		(32 "In15.Cu" signal "IN6")
		(34 "In16.Cu" signal "GND7")
		(2 "B.Cu" signal "BOTTOM")
		(9 "F.Adhes" user "F.Adhesive")
		(11 "B.Adhes" user "B.Adhesive")
		(13 "F.Paste" user "Package Geometry/Pastemask Top")
		(15 "B.Paste" user "Package Geometry/Pastemask Bottom")
		(5 "F.SilkS" user "Ref Des/Silkscreen Top")
		(7 "B.SilkS" user "Ref Des/Silkscreen Bottom")
		(1 "F.Mask" user "Board Geometry/Soldermask Top")
		(3 "B.Mask" user "Board Geometry/Soldermask Bottom")
		(17 "Dwgs.User" user "User.Drawings")
		(19 "Cmts.User" user "User.Comments")
		(21 "Eco1.User" user "User.Eco1")
		(23 "Eco2.User" user "User.Eco2")
		(25 "Edge.Cuts" user "Board Geometry/Outline")
		(27 "Margin" user)
		(31 "F.CrtYd" user "Package Geometry/Place Bound Top")
		(29 "B.CrtYd" user "Package Geometry/Place Bound Bottom")
		(35 "F.Fab" user "Ref Des/Assembly Top")
		(33 "B.Fab" user "Ref Des/Assembly Bottom")
	)
	(footprint ""
		(layer "F.Cu")
		(at 436.526432 -27.275536 90)
		(property "Reference" "PR3840"
			(at 0 0 90)
			(layer "F.SilkS")
			(hide yes)
			(effects
				(font
					(size 1.27 1.27)
				)
			)
		)
		(property "Value" ""
			(at 0 0 90)
			(layer "F.Fab")
			(effects
				(font
					(size 1.27 1.27)
				)
			)
		)
		(duplicate_pad_numbers_are_jumpers no)
		(fp_line
			(start 0.7874 -0.4064)
			(end 0.7874 0.4064)
			(stroke
				(width 0.1524)
				(type default)
			)
			(layer "F.SilkS")
		)
		(fp_line
			(start -0.7874 -0.4064)
			(end 0.7874 -0.4064)
			(stroke
				(width 0.1524)
				(type default)
			)
			(layer "F.SilkS")
		)
		(fp_line
			(start 0.7874 0.4064)
			(end -0.7874 0.4064)
			(stroke
				(width 0.1524)
				(type default)
			)
			(layer "F.SilkS")
		)
		(fp_line
			(start -0.7874 0.4064)
			(end -0.7874 -0.4064)
			(stroke
				(width 0.1524)
				(type default)
			)
			(layer "F.SilkS")
		)
		(fp_line
			(start -0.12065 -0.305054)
			(end -0.12065 -0.2794)
			(stroke
				(width 0.1)
				(type default)
			)
			(layer "F.Fab")
		)
		(fp_line
			(start -0.67945 -0.305054)
			(end -0.12065 -0.305054)
			(stroke
				(width 0.1)
				(type default)
			)
			(layer "F.Fab")
		)
		(fp_line
			(start 0.67945 -0.3048)
			(end 0.67945 0.3048)
			(stroke
				(width 0.1)
				(type default)
			)
			(layer "F.Fab")
		)
		(fp_line
			(start 0.12065 -0.3048)
			(end 0.67945 -0.3048)
			(stroke
				(width 0.1)
				(type default)
			)
			(layer "F.Fab")
		)
		(fp_line
			(start 0.12065 -0.2794)
			(end 0.12065 -0.3048)
			(stroke
				(width 0.1)
				(type default)
			)
			(layer "F.Fab")
		)
		(fp_line
			(start -0.12065 -0.2794)
			(end 0.12065 -0.2794)
			(stroke
				(width 0.1)
				(type default)
			)
			(layer "F.Fab")
		)
		(fp_line
			(start 0.120396 0.2794)
			(end -0.12065 0.2794)
			(stroke
				(width 0.1)
				(type default)
			)
			(layer "F.Fab")
		)
		(fp_line
			(start -0.12065 0.2794)
			(end -0.12065 0.3048)
			(stroke
				(width 0.1)
				(type default)
			)
			(layer "F.Fab")
		)
		(fp_line
			(start 0.67945 0.3048)
			(end 0.120396 0.3048)
			(stroke
				(width 0.1)
				(type default)
			)
			(layer "F.Fab")
		)
		(fp_line
			(start 0.120396 0.3048)
			(end 0.120396 0.2794)
			(stroke
				(width 0.1)
				(type default)
			)
			(layer "F.Fab")
		)
		(fp_line
			(start -0.12065 0.3048)
			(end -0.67945 0.3048)
			(stroke
				(width 0.1)
				(type default)
			)
			(layer "F.Fab")
		)
		(fp_line
			(start -0.67945 0.3048)
			(end -0.67945 -0.305054)
			(stroke
				(width 0.1)
				(type default)
			)
			(layer "F.Fab")
		)
		(pad "1" smd circle
			(at -0.40005 0 90)
			(size 0 0)
			(layers "F.Cu" "F.Mask" "F.Paste")
			(net "P12V_OCP_SFF")
		)
		(pad "2" smd circle
			(at 0.40005 0 90)
			(size 0 0)
			(layers "F.Cu" "F.Mask" "F.Paste")
			(net "P12V_OCP_OV_FB_1")
		)
	)
	(footprint ""
		(layer "F.Cu")
		(at 106.322114 -260.36524 -90)
		(property "Reference" "C435"
			(at 0 0 270)
			(layer "F.SilkS")
			(hide yes)
			(effects
				(font
					(size 1.27 1.27)
				)
			)
		)
		(property "Value" ""
			(at 0 0 270)
			(layer "F.Fab")
			(effects
				(font
					(size 1.27 1.27)
				)
			)
		)
		(duplicate_pad_numbers_are_jumpers no)
		(fp_line
			(start -0.7874 0.4064)
			(end -0.7874 -0.4064)
			(stroke
				(width 0.1524)
				(type default)
			)
			(layer "F.SilkS")
		)
		(fp_line
			(start 0.7874 0.4064)
			(end -0.7874 0.4064)
			(stroke
				(width 0.1524)
				(type default)
			)
			(layer "F.SilkS")
		)
		(fp_line
			(start -0.7874 -0.4064)
			(end 0.7874 -0.4064)
			(stroke
				(width 0.1524)
				(type default)
			)
			(layer "F.SilkS")
		)
		(fp_line
			(start 0.7874 -0.4064)
			(end 0.7874 0.4064)
			(stroke
				(width 0.1524)
				(type default)
			)
			(layer "F.SilkS")
		)
		(fp_line
			(start -0.67945 0.3048)
			(end -0.67945 -0.305054)
			(stroke
				(width 0.1)
				(type default)
			)
			(layer "F.Fab")
		)
		(fp_line
			(start -0.12065 0.3048)
			(end -0.67945 0.3048)
			(stroke
				(width 0.1)
				(type default)
			)
			(layer "F.Fab")
		)
		(fp_line
			(start 0.120396 0.3048)
			(end 0.120396 0.2794)
			(stroke
				(width 0.1)
				(type default)
			)
			(layer "F.Fab")
		)
		(fp_line
			(start 0.67945 0.3048)
			(end 0.120396 0.3048)
			(stroke
				(width 0.1)
				(type default)
			)
			(layer "F.Fab")
		)
		(fp_line
			(start -0.12065 0.2794)
			(end -0.12065 0.3048)
			(stroke
				(width 0.1)
				(type default)
			)
			(layer "F.Fab")
		)
		(fp_line
			(start 0.120396 0.2794)
			(end -0.12065 0.2794)
			(stroke
				(width 0.1)
				(type default)
			)
			(layer "F.Fab")
		)
		(fp_line
			(start -0.12065 -0.2794)
			(end 0.12065 -0.2794)
			(stroke
				(width 0.1)
				(type default)
			)
			(layer "F.Fab")
		)
		(fp_line
			(start 0.12065 -0.2794)
			(end 0.12065 -0.3048)
			(stroke
				(width 0.1)
				(type default)
			)
			(layer "F.Fab")
		)
		(fp_line
			(start 0.12065 -0.3048)
			(end 0.67945 -0.3048)
			(stroke
				(width 0.1)
				(type default)
			)
			(layer "F.Fab")
		)
		(fp_line
			(start 0.67945 -0.3048)
			(end 0.67945 0.3048)
			(stroke
				(width 0.1)
				(type default)
			)
			(layer "F.Fab")
		)
		(fp_line
			(start -0.67945 -0.305054)
			(end -0.12065 -0.305054)
			(stroke
				(width 0.1)
				(type default)
			)
			(layer "F.Fab")
		)
		(fp_line
			(start -0.12065 -0.305054)
			(end -0.12065 -0.2794)
			(stroke
				(width 0.1)
				(type default)
			)
			(layer "F.Fab")
		)
		(pad "1" smd circle
			(at -0.40005 0 270)
			(size 0 0)
			(layers "F.Cu" "F.Mask" "F.Paste")
			(net "PVCCFA_EHV_FIVRA_CPU1")
		)
		(pad "2" smd circle
			(at 0.40005 0 270)
			(size 0 0)
			(layers "F.Cu" "F.Mask" "F.Paste")
			(net "GND")
		)
	)
)
